(kicad_pcb
	(version 20260206)
	(generator "pcbnew")
	(generator_version "10.0")
	(general
		(thickness 1.6)
		(legacy_teardrops no)
	)
	(paper "A4")
	(title_block
		(title "04192023_DAF0TMB3IC0_F0TG_MB_C_brd_V02_OCP.brd")
		(comment 1 "Grand Teton / footprints 5579-5586 of 8354")
	)
	(layers
		(0 "F.Cu" signal "TOP")
		(4 "In1.Cu" signal "GND")
		(6 "In2.Cu" signal "IN1")
		(8 "In3.Cu" signal "GND1")
		(10 "In4.Cu" signal "IN2")
		(12 "In5.Cu" signal "GND2")
		(14 "In6.Cu" signal "IN3")
		(16 "In7.Cu" signal "GND3")
		(18 "In8.Cu" signal "VCC")
		(20 "In9.Cu" signal "VCC1")
		(22 "In10.Cu" signal "GND4")
		(24 "In11.Cu" signal "IN4")
		(26 "In12.Cu" signal "GND5")
		(28 "In13.Cu" signal "IN5")
		(30 "In14.Cu" signal "GND6")
		(32 "In15.Cu" signal "IN6")
		(34 "In16.Cu" signal "GND7")
		(2 "B.Cu" signal "BOTTOM")
		(9 "F.Adhes" user "F.Adhesive")
		(11 "B.Adhes" user "B.Adhesive")
		(13 "F.Paste" user "Package Geometry/Pastemask Top")
		(15 "B.Paste" user "Package Geometry/Pastemask Bottom")
		(5 "F.SilkS" user "Ref Des/Silkscreen Top")
		(7 "B.SilkS" user "Ref Des/Silkscreen Bottom")
		(1 "F.Mask" user "Board Geometry/Soldermask Top")
		(3 "B.Mask" user "Board Geometry/Soldermask Bottom")
		(17 "Dwgs.User" user "User.Drawings")
		(19 "Cmts.User" user "User.Comments")
		(21 "Eco1.User" user "User.Eco1")
		(23 "Eco2.User" user "User.Eco2")
		(25 "Edge.Cuts" user "Board Geometry/Outline")
		(27 "Margin" user)
		(31 "F.CrtYd" user "Package Geometry/Place Bound Top")
		(29 "B.CrtYd" user "Package Geometry/Place Bound Bottom")
		(35 "F.Fab" user "Ref Des/Assembly Top")
		(33 "B.Fab" user "Ref Des/Assembly Bottom")
	)
	(footprint ""
		(layer "B.Cu")
		(at 88.138 -146.939 180)
		(property "Reference" "PR8010"
			(at 0 0 0)
			(layer "B.SilkS")
			(hide yes)
			(effects
				(font
					(size 1.27 1.27)
				)
				(justify mirror)
			)
		)
		(property "Value" ""
			(at 0 0 0)
			(layer "B.Fab")
			(effects
				(font
					(size 1.27 1.27)
				)
				(justify mirror)
			)
		)
		(duplicate_pad_numbers_are_jumpers no)
		(fp_line
			(start 0.7874 0.4064)
			(end 0.7874 -0.4064)
			(stroke
				(width 0.1524)
				(type default)
			)
			(layer "B.SilkS")
		)
		(fp_line
			(start 0.7874 -0.4064)
			(end -0.7874 -0.4064)
			(stroke
				(width 0.1524)
				(type default)
			)
			(layer "B.SilkS")
		)
		(fp_line
			(start -0.7874 0.4064)
			(end 0.7874 0.4064)
			(stroke
				(width 0.1524)
				(type default)
			)
			(layer "B.SilkS")
		)
		(fp_line
			(start -0.7874 -0.4064)
			(end -0.7874 0.4064)
			(stroke
				(width 0.1524)
				(type default)
			)
			(layer "B.SilkS")
		)
		(fp_line
			(start 0.67945 0.3048)
			(end 0.67945 -0.305054)
			(stroke
				(width 0.1)
				(type default)
			)
			(layer "B.Fab")
		)
		(fp_line
			(start 0.67945 -0.305054)
			(end 0.12065 -0.305054)
			(stroke
				(width 0.1)
				(type default)
			)
			(layer "B.Fab")
		)
		(fp_line
			(start 0.12065 0.3048)
			(end 0.67945 0.3048)
			(stroke
				(width 0.1)
				(type default)
			)
			(layer "B.Fab")
		)
		(fp_line
			(start 0.12065 0.2794)
			(end 0.12065 0.3048)
			(stroke
				(width 0.1)
				(type default)
			)
			(layer "B.Fab")
		)
		(fp_line
			(start 0.12065 -0.2794)
			(end -0.12065 -0.2794)
			(stroke
				(width 0.1)
				(type default)
			)
			(layer "B.Fab")
		)
		(fp_line
			(start 0.12065 -0.305054)
			(end 0.12065 -0.2794)
			(stroke
				(width 0.1)
				(type default)
			)
			(layer "B.Fab")
		)
		(fp_line
			(start -0.120396 0.3048)
			(end -0.120396 0.2794)
			(stroke
				(width 0.1)
				(type default)
			)
			(layer "B.Fab")
		)
		(fp_line
			(start -0.120396 0.2794)
			(end 0.12065 0.2794)
			(stroke
				(width 0.1)
				(type default)
			)
			(layer "B.Fab")
		)
		(fp_line
			(start -0.12065 -0.2794)
			(end -0.12065 -0.3048)
			(stroke
				(width 0.1)
				(type default)
			)
			(layer "B.Fab")
		)
		(fp_line
			(start -0.12065 -0.3048)
			(end -0.67945 -0.3048)
			(stroke
				(width 0.1)
				(type default)
			)
			(layer "B.Fab")
		)
		(fp_line
			(start -0.67945 0.3048)
			(end -0.120396 0.3048)
			(stroke
				(width 0.1)
				(type default)
			)
			(layer "B.Fab")
		)
		(fp_line
			(start -0.67945 -0.3048)
			(end -0.67945 0.3048)
			(stroke
				(width 0.1)
				(type default)
			)
			(layer "B.Fab")
		)
		(pad "1" smd circle
			(at 0.40005 0)
			(size 0 0)
			(layers "B.Cu" "B.Mask" "B.Paste")
			(net "SVID_PVDDCR_CPU0_P1_SVD_R")
		)
		(pad "2" smd circle
			(at -0.40005 0)
			(size 0 0)
			(layers "B.Cu" "B.Mask" "B.Paste")
			(net "SVID_PVDDCR_CPU0_P1_SVD_R1")
		)
	)
	(footprint ""
		(layer "B.Cu")
		(at 68.916296 -387.084062 -90)
		(property "Reference" "C114"
			(at 0 0 90)
			(layer "B.SilkS")
			(hide yes)
			(effects
				(font
					(size 1.27 1.27)
				)
				(justify mirror)
			)
		)
		(property "Value" ""
			(at 0 0 90)
			(layer "B.Fab")
			(effects
				(font
					(size 1.27 1.27)
				)
				(justify mirror)
			)
		)
		(duplicate_pad_numbers_are_jumpers no)
		(fp_line
			(start -1.524 0.762)
			(end 1.524 0.762)
			(stroke
				(width 0.1524)
				(type default)
			)
			(layer "B.SilkS")
		)
		(fp_line
			(start 1.524 0.762)
			(end 1.524 -0.762)
			(stroke
				(width 0.1524)
				(type default)
			)
			(layer "B.SilkS")
		)
		(fp_line
			(start -1.524 -0.762)
			(end -1.524 0.762)
			(stroke
				(width 0.1524)
				(type default)
			)
			(layer "B.SilkS")
		)
		(fp_line
			(start 1.524 -0.762)
			(end -1.524 -0.762)
			(stroke
				(width 0.1524)
				(type default)
			)
			(layer "B.SilkS")
		)
		(fp_line
			(start -1.1049 0.724916)
			(end -1.1049 -0.724916)
			(stroke
				(width 0.1)
				(type default)
			)
			(layer "B.Fab")
		)
		(fp_line
			(start 1.1049 0.724916)
			(end -1.1049 0.724916)
			(stroke
				(width 0.1)
				(type default)
			)
			(layer "B.Fab")
		)
		(fp_line
			(start -1.1049 -0.724916)
			(end 1.1049 -0.724916)
			(stroke
				(width 0.1)
				(type default)
			)
			(layer "B.Fab")
		)
		(fp_line
			(start 1.1049 -0.724916)
			(end 1.1049 0.724916)
			(stroke
				(width 0.1)
				(type default)
			)
			(layer "B.Fab")
		)
		(pad "1" smd rect
			(at 0.889 0 270)
			(size 1.016 1.27)
			(layers "B.Cu" "B.Mask" "B.Paste")
			(net "P1V8_CPU1_RT0_1A")
		)
		(pad "2" smd rect
			(at -0.889 0 270)
			(size 1.016 1.27)
			(layers "B.Cu" "B.Mask" "B.Paste")
			(net "GND")
		)
	)
	(footprint ""
		(layer "B.Cu")
		(at 164.42817 -192.66027 180)
		(property "Reference" "C531"
			(at 0 0 0)
			(layer "B.SilkS")
			(hide yes)
			(effects
				(font
					(size 1.27 1.27)
				)
				(justify mirror)
			)
		)
		(property "Value" ""
			(at 0 0 0)
			(layer "B.Fab")
			(effects
				(font
					(size 1.27 1.27)
				)
				(justify mirror)
			)
		)
		(duplicate_pad_numbers_are_jumpers no)
		(fp_line
			(start 1.524 0.762)
			(end 1.524 -0.762)
			(stroke
				(width 0.1524)
				(type default)
			)
			(layer "B.SilkS")
		)
		(fp_line
			(start 1.524 -0.762)
			(end -1.524 -0.762)
			(stroke
				(width 0.1524)
				(type default)
			)
			(layer "B.SilkS")
		)
		(fp_line
			(start -1.524 0.762)
			(end 1.524 0.762)
			(stroke
				(width 0.1524)
				(type default)
			)
			(layer "B.SilkS")
		)
		(fp_line
			(start -1.524 -0.762)
			(end -1.524 0.762)
			(stroke
				(width 0.1524)
				(type default)
			)
			(layer "B.SilkS")
		)
		(fp_line
			(start 1.1049 0.724916)
			(end -1.1049 0.724916)
			(stroke
				(width 0.1)
				(type default)
			)
			(layer "B.Fab")
		)
		(fp_line
			(start 1.1049 -0.724916)
			(end 1.1049 0.724916)
			(stroke
				(width 0.1)
				(type default)
			)
			(layer "B.Fab")
		)
		(fp_line
			(start -1.1049 0.724916)
			(end -1.1049 -0.724916)
			(stroke
				(width 0.1)
				(type default)
			)
			(layer "B.Fab")
		)
		(fp_line
			(start -1.1049 -0.724916)
			(end 1.1049 -0.724916)
			(stroke
				(width 0.1)
				(type default)
			)
			(layer "B.Fab")
		)
		(pad "1" smd rect
			(at 0.889 0 180)
			(size 1.016 1.27)
			(layers "B.Cu" "B.Mask" "B.Paste")
			(net "P12V_MEM_CPU1")
		)
		(pad "2" smd rect
			(at -0.889 0 180)
			(size 1.016 1.27)
			(layers "B.Cu" "B.Mask" "B.Paste")
			(net "GND")
		)
	)
	(footprint ""
		(layer "B.Cu")
		(at 49.791366 -390.560052 90)
		(property "Reference" "C227"
			(at 0 0 90)
			(layer "B.SilkS")
			(hide yes)
			(effects
				(font
					(size 1.27 1.27)
				)
				(justify mirror)
			)
		)
		(property "Value" ""
			(at 0 0 90)
			(layer "B.Fab")
			(effects
				(font
					(size 1.27 1.27)
				)
				(justify mirror)
			)
		)
		(duplicate_pad_numbers_are_jumpers no)
		(fp_line
			(start 0.7874 -0.4064)
			(end -0.7874 -0.4064)
			(stroke
				(width 0.1524)
				(type default)
			)
			(layer "B.SilkS")
		)
		(fp_line
			(start -0.7874 -0.4064)
			(end -0.7874 0.4064)
			(stroke
				(width 0.1524)
				(type default)
			)
			(layer "B.SilkS")
		)
		(fp_line
			(start 0.7874 0.4064)
			(end 0.7874 -0.4064)
			(stroke
				(width 0.1524)
				(type default)
			)
			(layer "B.SilkS")
		)
		(fp_line
			(start -0.7874 0.4064)
			(end 0.7874 0.4064)
			(stroke
				(width 0.1524)
				(type default)
			)
			(layer "B.SilkS")
		)
		(fp_line
			(start 0.67945 -0.305054)
			(end 0.12065 -0.305054)
			(stroke
				(width 0.1)
				(type default)
			)
			(layer "B.Fab")
		)
		(fp_line
			(start 0.12065 -0.305054)
			(end 0.12065 -0.2794)
			(stroke
				(width 0.1)
				(type default)
			)
			(layer "B.Fab")
		)
		(fp_line
			(start -0.12065 -0.3048)
			(end -0.67945 -0.3048)
			(stroke
				(width 0.1)
				(type default)
			)
			(layer "B.Fab")
		)
		(fp_line
			(start -0.67945 -0.3048)
			(end -0.67945 0.3048)
			(stroke
				(width 0.1)
				(type default)
			)
			(layer "B.Fab")
		)
		(fp_line
			(start 0.12065 -0.2794)
			(end -0.12065 -0.2794)
			(stroke
				(width 0.1)
				(type default)
			)
			(layer "B.Fab")
		)
		(fp_line
			(start -0.12065 -0.2794)
			(end -0.12065 -0.3048)
			(stroke
				(width 0.1)
				(type default)
			)
			(layer "B.Fab")
		)
		(fp_line
			(start 0.12065 0.2794)
			(end 0.12065 0.3048)
			(stroke
				(width 0.1)
				(type default)
			)
			(layer "B.Fab")
		)
		(fp_line
			(start -0.120396 0.2794)
			(end 0.12065 0.2794)
			(stroke
				(width 0.1)
				(type default)
			)
			(layer "B.Fab")
		)
		(fp_line
			(start 0.67945 0.3048)
			(end 0.67945 -0.305054)
			(stroke
				(width 0.1)
				(type default)
			)
			(layer "B.Fab")
		)
		(fp_line
			(start 0.12065 0.3048)
			(end 0.67945 0.3048)
			(stroke
				(width 0.1)
				(type default)
			)
			(layer "B.Fab")
		)
		(fp_line
			(start -0.120396 0.3048)
			(end -0.120396 0.2794)
			(stroke
				(width 0.1)
				(type default)
			)
			(layer "B.Fab")
		)
		(fp_line
			(start -0.67945 0.3048)
			(end -0.120396 0.3048)
			(stroke
				(width 0.1)
				(type default)
			)
			(layer "B.Fab")
		)
		(pad "1" smd circle
			(at 0.40005 0 270)
			(size 0 0)
			(layers "B.Cu" "B.Mask" "B.Paste")
			(net "P0V9_CPU1_RT0_2A")
		)
		(pad "2" smd circle
			(at -0.40005 0 270)
			(size 0 0)
			(layers "B.Cu" "B.Mask" "B.Paste")
			(net "GND")
		)
	)
	(footprint ""
		(layer "B.Cu")
		(at 216.027 -335.153 90)
		(property "Reference" "R6719"
			(at 0 0 90)
			(layer "B.SilkS")
			(hide yes)
			(effects
				(font
					(size 1.27 1.27)
				)
				(justify mirror)
			)
		)
		(property "Value" ""
			(at 0 0 90)
			(layer "B.Fab")
			(effects
				(font
					(size 1.27 1.27)
				)
				(justify mirror)
			)
		)
		(duplicate_pad_numbers_are_jumpers no)
		(fp_line
			(start 0.32512 -0.175006)
			(end -0.32512 -0.175006)
			(stroke
				(width 0.1)
				(type default)
			)
			(layer "B.Fab")
		)
		(fp_line
			(start -0.32512 -0.175006)
			(end -0.32512 0.175006)
			(stroke
				(width 0.1)
				(type default)
			)
			(layer "B.Fab")
		)
		(fp_line
			(start 0.32512 0.175006)
			(end 0.32512 -0.175006)
			(stroke
				(width 0.1)
				(type default)
			)
			(layer "B.Fab")
		)
		(fp_line
			(start -0.32512 0.175006)
			(end 0.32512 0.175006)
			(stroke
				(width 0.1)
				(type default)
			)
			(layer "B.Fab")
		)
		(pad "1" smd rect
			(at 0.2667 0 270)
			(size 0.3048 0.381)
			(layers "B.Cu" "B.Mask" "B.Paste")
			(net "P1V8_CPU1_RT_1D")
		)
		(pad "2" smd rect
			(at -0.2667 0 90)
			(size 0.3048 0.381)
			(layers "B.Cu" "B.Mask" "B.Paste")
			(net "SMB_RT_CPU1_P0_R_SCL")
		)
	)
	(footprint ""
		(layer "B.Cu")
		(at 354.152454 -253.43231)
		(property "Reference" "C2569"
			(at 0 0 0)
			(layer "B.SilkS")
			(hide yes)
			(effects
				(font
					(size 1.27 1.27)
				)
				(justify mirror)
			)
		)
		(property "Value" ""
			(at 0 0 0)
			(layer "B.Fab")
			(effects
				(font
					(size 1.27 1.27)
				)
				(justify mirror)
			)
		)
		(duplicate_pad_numbers_are_jumpers no)
		(fp_line
			(start -0.7874 -0.4064)
			(end -0.7874 0.4064)
			(stroke
				(width 0.1524)
				(type default)
			)
			(layer "B.SilkS")
		)
		(fp_line
			(start -0.7874 0.4064)
			(end 0.7874 0.4064)
			(stroke
				(width 0.1524)
				(type default)
			)
			(layer "B.SilkS")
		)
		(fp_line
			(start 0.7874 -0.4064)
			(end -0.7874 -0.4064)
			(stroke
				(width 0.1524)
				(type default)
			)
			(layer "B.SilkS")
		)
		(fp_line
			(start 0.7874 0.4064)
			(end 0.7874 -0.4064)
			(stroke
				(width 0.1524)
				(type default)
			)
			(layer "B.SilkS")
		)
		(fp_line
			(start -0.67945 -0.3048)
			(end -0.67945 0.3048)
			(stroke
				(width 0.1)
				(type default)
			)
			(layer "B.Fab")
		)
		(fp_line
			(start -0.67945 0.3048)
			(end -0.120396 0.3048)
			(stroke
				(width 0.1)
				(type default)
			)
			(layer "B.Fab")
		)
		(fp_line
			(start -0.12065 -0.3048)
			(end -0.67945 -0.3048)
			(stroke
				(width 0.1)
				(type default)
			)
			(layer "B.Fab")
		)
		(fp_line
			(start -0.12065 -0.2794)
			(end -0.12065 -0.3048)
			(stroke
				(width 0.1)
				(type default)
			)
			(layer "B.Fab")
		)
		(fp_line
			(start -0.120396 0.2794)
			(end 0.12065 0.2794)
			(stroke
				(width 0.1)
				(type default)
			)
			(layer "B.Fab")
		)
		(fp_line
			(start -0.120396 0.3048)
			(end -0.120396 0.2794)
			(stroke
				(width 0.1)
				(type default)
			)
			(layer "B.Fab")
		)
		(fp_line
			(start 0.12065 -0.305054)
			(end 0.12065 -0.2794)
			(stroke
				(width 0.1)
				(type default)
			)
			(layer "B.Fab")
		)
		(fp_line
			(start 0.12065 -0.2794)
			(end -0.12065 -0.2794)
			(stroke
				(width 0.1)
				(type default)
			)
			(layer "B.Fab")
		)
		(fp_line
			(start 0.12065 0.2794)
			(end 0.12065 0.3048)
			(stroke
				(width 0.1)
				(type default)
			)
			(layer "B.Fab")
		)
		(fp_line
			(start 0.12065 0.3048)
			(end 0.67945 0.3048)
			(stroke
				(width 0.1)
				(type default)
			)
			(layer "B.Fab")
		)
		(fp_line
			(start 0.67945 -0.305054)
			(end 0.12065 -0.305054)
			(stroke
				(width 0.1)
				(type default)
			)
			(layer "B.Fab")
		)
		(fp_line
			(start 0.67945 0.3048)
			(end 0.67945 -0.305054)
			(stroke
				(width 0.1)
				(type default)
			)
			(layer "B.Fab")
		)
		(pad "1" smd circle
			(at 0.40005 0 180)
			(size 0 0)
			(layers "B.Cu" "B.Mask" "B.Paste")
			(net "PVDDCR_SOC_P0")
		)
		(pad "2" smd circle
			(at -0.40005 0 180)
			(size 0 0)
			(layers "B.Cu" "B.Mask" "B.Paste")
			(net "GND")
		)
	)
	(footprint ""
		(layer "B.Cu")
		(at 134.262114 -32.818578 180)
		(property "Reference" "C6053"
			(at 0 0 0)
			(layer "B.SilkS")
			(hide yes)
			(effects
				(font
					(size 1.27 1.27)
				)
				(justify mirror)
			)
		)
		(property "Value" ""
			(at 0 0 0)
			(layer "B.Fab")
			(effects
				(font
					(size 1.27 1.27)
				)
				(justify mirror)
			)
		)
		(duplicate_pad_numbers_are_jumpers no)
		(fp_line
			(start 0.7874 0.4064)
			(end 0.7874 -0.4064)
			(stroke
				(width 0.1524)
				(type default)
			)
			(layer "B.SilkS")
		)
		(fp_line
			(start 0.7874 -0.4064)
			(end -0.7874 -0.4064)
			(stroke
				(width 0.1524)
				(type default)
			)
			(layer "B.SilkS")
		)
		(fp_line
			(start -0.7874 0.4064)
			(end 0.7874 0.4064)
			(stroke
				(width 0.1524)
				(type default)
			)
			(layer "B.SilkS")
		)
		(fp_line
			(start -0.7874 -0.4064)
			(end -0.7874 0.4064)
			(stroke
				(width 0.1524)
				(type default)
			)
			(layer "B.SilkS")
		)
		(fp_line
			(start 0.67945 0.3048)
			(end 0.67945 -0.305054)
			(stroke
				(width 0.1)
				(type default)
			)
			(layer "B.Fab")
		)
		(fp_line
			(start 0.67945 -0.305054)
			(end 0.12065 -0.305054)
			(stroke
				(width 0.1)
				(type default)
			)
			(layer "B.Fab")
		)
		(fp_line
			(start 0.12065 0.3048)
			(end 0.67945 0.3048)
			(stroke
				(width 0.1)
				(type default)
			)
			(layer "B.Fab")
		)
		(fp_line
			(start 0.12065 0.2794)
			(end 0.12065 0.3048)
			(stroke
				(width 0.1)
				(type default)
			)
			(layer "B.Fab")
		)
		(fp_line
			(start 0.12065 -0.2794)
			(end -0.12065 -0.2794)
			(stroke
				(width 0.1)
				(type default)
			)
			(layer "B.Fab")
		)
		(fp_line
			(start 0.12065 -0.305054)
			(end 0.12065 -0.2794)
			(stroke
				(width 0.1)
				(type default)
			)
			(layer "B.Fab")
		)
		(fp_line
			(start -0.120396 0.3048)
			(end -0.120396 0.2794)
			(stroke
				(width 0.1)
				(type default)
			)
			(layer "B.Fab")
		)
		(fp_line
			(start -0.120396 0.2794)
			(end 0.12065 0.2794)
			(stroke
				(width 0.1)
				(type default)
			)
			(layer "B.Fab")
		)
		(fp_line
			(start -0.12065 -0.2794)
			(end -0.12065 -0.3048)
			(stroke
				(width 0.1)
				(type default)
			)
			(layer "B.Fab")
		)
		(fp_line
			(start -0.12065 -0.3048)
			(end -0.67945 -0.3048)
			(stroke
				(width 0.1)
				(type default)
			)
			(layer "B.Fab")
		)
		(fp_line
			(start -0.67945 0.3048)
			(end -0.120396 0.3048)
			(stroke
				(width 0.1)
				(type default)
			)
			(layer "B.Fab")
		)
		(fp_line
			(start -0.67945 -0.3048)
			(end -0.67945 0.3048)
			(stroke
				(width 0.1)
				(type default)
			)
			(layer "B.Fab")
		)
		(pad "1" smd circle
			(at 0.40005 0)
			(size 0 0)
			(layers "B.Cu" "B.Mask" "B.Paste")
			(net "P3V3_AUX")
		)
		(pad "2" smd circle
			(at -0.40005 0)
			(size 0 0)
			(layers "B.Cu" "B.Mask" "B.Paste")
			(net "GND")
		)
	)
	(footprint ""
		(layer "B.Cu")
		(at 325.861426 -400.19605 180)
		(property "Reference" "C550"
			(at 0 0 0)
			(layer "B.SilkS")
			(hide yes)
			(effects
				(font
					(size 1.27 1.27)
				)
				(justify mirror)
			)
		)
		(property "Value" ""
			(at 0 0 0)
			(layer "B.Fab")
			(effects
				(font
					(size 1.27 1.27)
				)
				(justify mirror)
			)
		)
		(duplicate_pad_numbers_are_jumpers no)
		(fp_line
			(start 1.524 0.762)
			(end 1.524 -0.762)
			(stroke
				(width 0.1524)
				(type default)
			)
			(layer "B.SilkS")
		)
		(fp_line
			(start 1.524 -0.762)
			(end -1.524 -0.762)
			(stroke
				(width 0.1524)
				(type default)
			)
			(layer "B.SilkS")
		)
		(fp_line
			(start -1.524 0.762)
			(end 1.524 0.762)
			(stroke
				(width 0.1524)
				(type default)
			)
			(layer "B.SilkS")
		)
		(fp_line
			(start -1.524 -0.762)
			(end -1.524 0.762)
			(stroke
				(width 0.1524)
				(type default)
			)
			(layer "B.SilkS")
		)
		(fp_line
			(start 1.1049 0.724916)
			(end -1.1049 0.724916)
			(stroke
				(width 0.1)
				(type default)
			)
			(layer "B.Fab")
		)
		(fp_line
			(start 1.1049 -0.724916)
			(end 1.1049 0.724916)
			(stroke
				(width 0.1)
				(type default)
			)
			(layer "B.Fab")
		)
		(fp_line
			(start -1.1049 0.724916)
			(end -1.1049 -0.724916)
			(stroke
				(width 0.1)
				(type default)
			)
			(layer "B.Fab")
		)
		(fp_line
			(start -1.1049 -0.724916)
			(end 1.1049 -0.724916)
			(stroke
				(width 0.1)
				(type default)
			)
			(layer "B.Fab")
		)
		(pad "1" smd rect
			(at 0.889 0 180)
			(size 1.016 1.27)
			(layers "B.Cu" "B.Mask" "B.Paste")
			(net "P0V9_CPU0_RT0_2A")
		)
		(pad "2" smd rect
			(at -0.889 0 180)
			(size 1.016 1.27)
			(layers "B.Cu" "B.Mask" "B.Paste")
			(net "GND")
		)
	)
)
